(kicad_pcb
	(version 20260206)
	(generator "pcbnew")
	(generator_version "10.0")
	(general
		(thickness 1.6)
		(legacy_teardrops no)
	)
	(paper "A4")
	(title_block
		(title "pdpb — Lightning_PDPB_BRD.brd")
		(comment 1 "Lightning (Wiwynn / Facebook NVMe JBOF) / footprint 737 of 1140 (CN7), pads 1-62 of 62")
	)
	(layers
		(0 "F.Cu" signal "TOP")
		(4 "In1.Cu" signal "L2GND")
		(6 "In2.Cu" signal "L3")
		(8 "In3.Cu" signal "L4VCC")
		(10 "In4.Cu" signal "L5VCC")
		(12 "In5.Cu" signal "L6")
		(14 "In6.Cu" signal "L7GND")
		(2 "B.Cu" signal "BOTTOM")
		(9 "F.Adhes" user "F.Adhesive")
		(11 "B.Adhes" user "B.Adhesive")
		(13 "F.Paste" user "Package Geometry/Pastemask Top")
		(15 "B.Paste" user "Package Geometry/Pastemask Bottom")
		(5 "F.SilkS" user "Ref Des/Silkscreen Top")
		(7 "B.SilkS" user "Ref Des/Silkscreen Bottom")
		(1 "F.Mask" user "Board Geometry/Soldermask Top")
		(3 "B.Mask" user "Board Geometry/Soldermask Bottom")
		(17 "Dwgs.User" user "User.Drawings")
		(19 "Cmts.User" user "User.Comments")
		(21 "Eco1.User" user "User.Eco1")
		(23 "Eco2.User" user "User.Eco2")
		(25 "Edge.Cuts" user "Board Geometry/Outline")
		(27 "Margin" user)
		(31 "F.CrtYd" user "Package Geometry/Place Bound Top")
		(29 "B.CrtYd" user "Package Geometry/Place Bound Bottom")
		(35 "F.Fab" user "Ref Des/Assembly Top")
		(33 "B.Fab" user "Ref Des/Assembly Bottom")
	)
	(footprint ""
		(layer "F.Cu")
		(at 259.899912 -409.949904 90)
		(property "Reference" "CN7"
			(at 0 0 90)
			(layer "F.SilkS")
			(hide yes)
			(effects
				(font
					(size 1.27 1.27)
				)
			)
		)
		(property "Value" "AMP-CONN60-5-GP"
			(at -32.935418 -14.620748 90)
			(unlocked yes)
			(layer "F.Fab")
			(hide yes)
			(effects
				(font
					(size 1.016 1.016)
					(thickness 0.1524)
				)
			)
		)
		(property "Device Type" "GPCE54362413HR"
			(at -32.935418 -16.144748 90)
			(unlocked yes)
			(layer "F.Fab")
			(hide yes)
			(effects
				(font
					(size 1.016 1.016)
					(thickness 0.1524)
				)
			)
		)
		(duplicate_pad_numbers_are_jumpers no)
		(pad "" np_thru_hole circle
			(at -50.279808 0 90)
			(size 0.254 0.254)
			(drill 3.7084)
			(layers "*.Cu" "*.Mask")
			(clearance 2.0828)
			(thermal_gap 2.0828)
		)
		(pad "" np_thru_hole circle
			(at 20.379944 0 90)
			(size 0.254 0.254)
			(drill 3.7084)
			(layers "*.Cu" "*.Mask")
			(clearance 2.0828)
			(thermal_gap 2.0828)
		)
		(pad "P1" smd rect
			(at -42.164 -8.377682 90)
			(size 0.0254 0.0254)
			(layers "F.Cu" "F.Mask" "F.Paste")
			(net "P12V")
		)
		(pad "P2" smd custom
			(at -41.060116 -8.377682 90)
			(size 2.3622 2.3622)
			(layers "F.Cu" "F.Mask" "F.Paste")
			(net "P12V")
			(options
				(clearance outline)
				(anchor circle)
			)
			(primitives
				(gr_poly
					(pts
						(xy -4.7244 5.0038) (xy -4.7244 -5.0038) (xy 4.7244 -5.0038) (xy 4.7244 5.0038) (xy 0.23495 5.0038)
						(xy 0.23495 -1.4986) (xy -0.23495 -1.4986) (xy -0.23495 5.0038)
					)
					(width 0)
					(fill yes)
				)
			)
		)
		(pad "P3" smd rect
			(at -39.878 -8.377682 90)
			(size 0.0254 0.0254)
			(layers "F.Cu" "F.Mask" "F.Paste")
			(net "P12V")
		)
		(pad "P4" smd rect
			(at -38.862 -8.377682 90)
			(size 0.0254 0.0254)
			(layers "F.Cu" "F.Mask" "F.Paste")
			(net "P12V")
		)
		(pad "P5" smd rect
			(at -32.004 -8.377682 90)
			(size 0.0254 0.0254)
			(layers "F.Cu" "F.Mask" "F.Paste")
			(net "P12V")
		)
		(pad "P6" smd custom
			(at -30.900116 -8.377682 90)
			(size 2.3622 2.3622)
			(layers "F.Cu" "F.Mask" "F.Paste")
			(net "P12V")
			(options
				(clearance outline)
				(anchor circle)
			)
			(primitives
				(gr_poly
					(pts
						(xy -4.7244 5.0038) (xy -4.7244 -5.0038) (xy 4.7244 -5.0038) (xy 4.7244 5.0038) (xy 0.23495 5.0038)
						(xy 0.23495 -1.4986) (xy -0.23495 -1.4986) (xy -0.23495 5.0038)
					)
					(width 0)
					(fill yes)
				)
			)
		)
		(pad "P7" smd rect
			(at -29.718 -8.377682 90)
			(size 0.0254 0.0254)
			(layers "F.Cu" "F.Mask" "F.Paste")
			(net "P12V")
		)
		(pad "P8" smd rect
			(at -28.702 -8.377682 90)
			(size 0.0254 0.0254)
			(layers "F.Cu" "F.Mask" "F.Paste")
			(net "P12V")
		)
		(pad "P9" smd rect
			(at -22.098 -8.377682 90)
			(size 0.0254 0.0254)
			(layers "F.Cu" "F.Mask" "F.Paste")
			(net "GND")
		)
		(pad "P10" smd custom
			(at -20.740116 -8.377682 90)
			(size 2.3622 2.3622)
			(layers "F.Cu" "F.Mask" "F.Paste")
			(net "GND")
			(options
				(clearance outline)
				(anchor circle)
			)
			(primitives
				(gr_poly
					(pts
						(xy -4.7244 5.0038) (xy -4.7244 -5.0038) (xy 4.7244 -5.0038) (xy 4.7244 5.0038) (xy 0.23495 5.0038)
						(xy 0.23495 -1.4986) (xy -0.23495 -1.4986) (xy -0.23495 5.0038)
					)
					(width 0)
					(fill yes)
				)
			)
		)
		(pad "P11" smd rect
			(at -19.558 -8.377682 90)
			(size 0.0254 0.0254)
			(layers "F.Cu" "F.Mask" "F.Paste")
			(net "GND")
		)
		(pad "P12" smd rect
			(at -18.542 -8.377682 90)
			(size 0.0254 0.0254)
			(layers "F.Cu" "F.Mask" "F.Paste")
			(net "GND")
		)
		(pad "P13" smd rect
			(at -11.938 -8.377682 90)
			(size 0.0254 0.0254)
			(layers "F.Cu" "F.Mask" "F.Paste")
			(net "GND")
		)
		(pad "P14" smd custom
			(at -10.580116 -8.377682 90)
			(size 2.3622 2.3622)
			(layers "F.Cu" "F.Mask" "F.Paste")
			(net "GND")
			(options
				(clearance outline)
				(anchor circle)
			)
			(primitives
				(gr_poly
					(pts
						(xy -4.7244 5.0038) (xy -4.7244 -5.0038) (xy 4.7244 -5.0038) (xy 4.7244 5.0038) (xy 0.23495 5.0038)
						(xy 0.23495 -1.4986) (xy -0.23495 -1.4986) (xy -0.23495 5.0038)
					)
					(width 0)
					(fill yes)
				)
			)
		)
		(pad "P15" smd rect
			(at -9.144 -8.377682 90)
			(size 0.0254 0.0254)
			(layers "F.Cu" "F.Mask" "F.Paste")
			(net "GND")
		)
		(pad "P16" smd rect
			(at -7.874 -8.377682 90)
			(size 0.0254 0.0254)
			(layers "F.Cu" "F.Mask" "F.Paste")
			(net "GND")
		)
		(pad "P17" smd rect
			(at -2.960116 -5.126736 90)
			(size 4.3688 10.0076)
			(drill
				(offset 0 -0.381)
			)
			(layers "F.Cu" "F.Mask" "F.Paste")
			(net "GND")
		)
		(pad "P18" smd rect
			(at -2.032 -5.126736 90)
			(size 0.0254 0.0254)
			(layers "F.Cu" "F.Mask" "F.Paste")
			(net "GND")
		)
		(pad "P19" smd rect
			(at -2.032 -5.507736 90)
			(size 0.0254 0.0254)
			(layers "F.Cu" "F.Mask" "F.Paste")
			(net "GND")
		)
		(pad "P20" smd rect
			(at -2.960116 -5.507736 90)
			(size 4.3688 10.0076)
			(layers "F.Cu" "F.Mask" "F.Paste")
			(net "GND")
		)
		(pad "P21" smd rect
			(at -7.874 -8.758682 90)
			(size 0.0254 0.0254)
			(layers "F.Cu" "F.Mask" "F.Paste")
			(net "GND")
		)
		(pad "P22" smd rect
			(at -9.144 -8.758682 90)
			(size 0.0254 0.0254)
			(layers "F.Cu" "F.Mask" "F.Paste")
			(net "GND")
		)
		(pad "P23" smd custom
			(at -10.580116 -8.758682 90)
			(size 2.3622 2.3622)
			(layers "F.Cu" "F.Mask" "F.Paste")
			(net "GND")
			(options
				(clearance outline)
				(anchor circle)
			)
			(primitives
				(gr_poly
					(pts
						(xy -4.7244 5.0038) (xy -4.7244 -5.0038) (xy 4.7244 -5.0038) (xy 4.7244 5.0038) (xy 0.23495 5.0038)
						(xy 0.23495 -1.4986) (xy -0.23495 -1.4986) (xy -0.23495 5.0038)
					)
					(width 0)
					(fill yes)
				)
			)
		)
		(pad "P24" smd rect
			(at -11.938 -8.758682 90)
			(size 0.0254 0.0254)
			(layers "F.Cu" "F.Mask" "F.Paste")
			(net "GND")
		)
		(pad "P25" smd rect
			(at -18.542 -8.758682 90)
			(size 0.0254 0.0254)
			(layers "F.Cu" "F.Mask" "F.Paste")
			(net "GND")
		)
		(pad "P26" smd rect
			(at -19.558 -8.758682 90)
			(size 0.0254 0.0254)
			(layers "F.Cu" "F.Mask" "F.Paste")
			(net "GND")
		)
		(pad "P27" smd custom
			(at -20.740116 -8.758682 90)
			(size 2.3622 2.3622)
			(layers "F.Cu" "F.Mask" "F.Paste")
			(net "GND")
			(options
				(clearance outline)
				(anchor circle)
			)
			(primitives
				(gr_poly
					(pts
						(xy -4.7244 5.0038) (xy -4.7244 -5.0038) (xy 4.7244 -5.0038) (xy 4.7244 5.0038) (xy 0.23495 5.0038)
						(xy 0.23495 -1.4986) (xy -0.23495 -1.4986) (xy -0.23495 5.0038)
					)
					(width 0)
					(fill yes)
				)
			)
		)
		(pad "P28" smd rect
			(at -22.098 -8.758682 90)
			(size 0.0254 0.0254)
			(layers "F.Cu" "F.Mask" "F.Paste")
			(net "GND")
		)
		(pad "P29" smd rect
			(at -28.702 -8.758682 90)
			(size 0.0254 0.0254)
			(layers "F.Cu" "F.Mask" "F.Paste")
			(net "P12V")
		)
		(pad "P30" smd rect
			(at -29.718 -8.758682 90)
			(size 0.0254 0.0254)
			(layers "F.Cu" "F.Mask" "F.Paste")
			(net "P12V")
		)
		(pad "P31" smd custom
			(at -30.900116 -8.758682 90)
			(size 2.3622 2.3622)
			(layers "F.Cu" "F.Mask" "F.Paste")
			(net "P12V")
			(options
				(clearance outline)
				(anchor circle)
			)
			(primitives
				(gr_poly
					(pts
						(xy -4.7244 5.0038) (xy -4.7244 -5.0038) (xy 4.7244 -5.0038) (xy 4.7244 5.0038) (xy 0.23495 5.0038)
						(xy 0.23495 -1.4986) (xy -0.23495 -1.4986) (xy -0.23495 5.0038)
					)
					(width 0)
					(fill yes)
				)
			)
		)
		(pad "P32" smd rect
			(at -32.004 -8.758682 90)
			(size 0.0254 0.0254)
			(layers "F.Cu" "F.Mask" "F.Paste")
			(net "P12V")
		)
		(pad "P33" smd rect
			(at -38.862 -8.758682 90)
			(size 0.0254 0.0254)
			(layers "F.Cu" "F.Mask" "F.Paste")
			(net "P12V")
		)
		(pad "P34" smd rect
			(at -39.878 -8.758682 90)
			(size 0.0254 0.0254)
			(layers "F.Cu" "F.Mask" "F.Paste")
			(net "P12V")
		)
		(pad "P35" smd custom
			(at -41.060116 -8.758682 90)
			(size 2.3622 2.3622)
			(layers "F.Cu" "F.Mask" "F.Paste")
			(net "P12V")
			(options
				(clearance outline)
				(anchor circle)
			)
			(primitives
				(gr_poly
					(pts
						(xy -4.7244 5.0038) (xy -4.7244 -5.0038) (xy 4.7244 -5.0038) (xy 4.7244 5.0038) (xy 0.23495 5.0038)
						(xy 0.23495 -1.4986) (xy -0.23495 -1.4986) (xy -0.23495 5.0038)
					)
					(width 0)
					(fill yes)
				)
			)
		)
		(pad "P36" smd rect
			(at -42.164 -8.758682 90)
			(size 0.0254 0.0254)
			(layers "F.Cu" "F.Mask" "F.Paste")
			(net "P12V")
		)
		(pad "S1" smd rect
			(at 1.810004 -3.805936 90)
			(size 0.8128 5.842)
			(drill
				(offset 0 0.381)
			)
			(layers "F.Cu" "F.Mask" "F.Paste")
			(net "GND")
		)
		(pad "S2" smd rect
			(at 3.080004 -3.805936 90)
			(size 0.8128 5.842)
			(drill
				(offset 0 0.381)
			)
			(layers "F.Cu" "F.Mask" "F.Paste")
			(net "P3V3")
		)
		(pad "S3" smd rect
			(at 4.350004 -3.805936 90)
			(size 0.8128 5.842)
			(drill
				(offset 0 0.381)
			)
			(layers "F.Cu" "F.Mask" "F.Paste")
			(net "P3V3")
		)
		(pad "S4" smd rect
			(at 5.620004 -3.805936 90)
			(size 0.8128 5.842)
			(drill
				(offset 0 0.381)
			)
			(layers "F.Cu" "F.Mask" "F.Paste")
			(net "PEER_TRAY_PRESENT")
		)
		(pad "S5" smd rect
			(at 6.890004 -3.805936 90)
			(size 0.8128 5.842)
			(drill
				(offset 0 0.381)
			)
			(layers "F.Cu" "F.Mask" "F.Paste")
			(net "N70914768")
		)
		(pad "S6" smd rect
			(at 8.160004 -3.805936 90)
			(size 0.8128 5.842)
			(drill
				(offset 0 0.381)
			)
			(layers "F.Cu" "F.Mask" "F.Paste")
			(net "SELF_TRAY_PRESENT")
		)
		(pad "S7" smd rect
			(at 9.430004 -3.805936 90)
			(size 0.8128 5.842)
			(drill
				(offset 0 0.381)
			)
			(layers "F.Cu" "F.Mask" "F.Paste")
			(net "PWM_EXP_A")
		)
		(pad "S8" smd rect
			(at 10.700004 -3.805936 90)
			(size 0.8128 5.842)
			(drill
				(offset 0 0.381)
			)
			(layers "F.Cu" "F.Mask" "F.Paste")
			(net "GND")
		)
		(pad "S9" smd rect
			(at 11.970004 -3.805936 90)
			(size 0.8128 5.842)
			(drill
				(offset 0 0.381)
			)
			(layers "F.Cu" "F.Mask" "F.Paste")
			(net "I2C_C_SDA")
		)
		(pad "S10" smd rect
			(at 13.240004 -3.805936 90)
			(size 0.8128 5.842)
			(drill
				(offset 0 0.381)
			)
			(layers "F.Cu" "F.Mask" "F.Paste")
			(net "GND")
		)
		(pad "S11" smd rect
			(at 14.510004 -3.805936 90)
			(size 0.8128 5.842)
			(drill
				(offset 0 0.381)
			)
			(layers "F.Cu" "F.Mask" "F.Paste")
			(net "I2C_C_SCL")
		)
		(pad "S12" smd rect
			(at 15.780004 -3.805936 90)
			(size 0.8128 5.842)
			(drill
				(offset 0 0.381)
			)
			(layers "F.Cu" "F.Mask" "F.Paste")
			(net "GND")
		)
		(pad "S13" smd rect
			(at 15.780004 -3.424936 90)
			(size 0.8128 5.842)
			(layers "F.Cu" "F.Mask" "F.Paste")
			(net "GND")
		)
		(pad "S14" smd rect
			(at 14.510004 -3.424936 90)
			(size 0.8128 5.842)
			(layers "F.Cu" "F.Mask" "F.Paste")
			(net "SELF_1A&2A_HB")
		)
		(pad "S15" smd rect
			(at 13.240004 -3.424936 90)
			(size 0.8128 5.842)
			(layers "F.Cu" "F.Mask" "F.Paste")
			(net "N70930468")
		)
		(pad "S16" smd rect
			(at 11.970004 -3.424936 90)
			(size 0.8128 5.842)
			(layers "F.Cu" "F.Mask" "F.Paste")
			(net "TRAY_ID")
		)
		(pad "S17" smd rect
			(at 10.700004 -3.424936 90)
			(size 0.8128 5.842)
			(layers "F.Cu" "F.Mask" "F.Paste")
			(net "FCB_HW_REVISION")
		)
		(pad "S18" smd rect
			(at 9.430004 -3.424936 90)
			(size 0.8128 5.842)
			(layers "F.Cu" "F.Mask" "F.Paste")
			(net "SD_LATCH_RELEASE")
		)
		(pad "S19" smd rect
			(at 8.160004 -3.424936 90)
			(size 0.8128 5.842)
			(layers "F.Cu" "F.Mask" "F.Paste")
			(net "GND")
		)
		(pad "S20" smd rect
			(at 6.890004 -3.424936 90)
			(size 0.8128 5.842)
			(layers "F.Cu" "F.Mask" "F.Paste")
			(net "PEER_1A&2A_HB")
		)
		(pad "S21" smd rect
			(at 5.620004 -3.424936 90)
			(size 0.8128 5.842)
			(layers "F.Cu" "F.Mask" "F.Paste")
			(net "N70929042")
		)
		(pad "S22" smd rect
			(at 4.350004 -3.424936 90)
			(size 0.8128 5.842)
			(layers "F.Cu" "F.Mask" "F.Paste")
			(net "GND")
		)
		(pad "S23" smd rect
			(at 3.080004 -3.424936 90)
			(size 0.8128 5.842)
			(layers "F.Cu" "F.Mask" "F.Paste")
			(net "GND")
		)
		(pad "S24" smd rect
			(at 1.810004 -3.424936 90)
			(size 0.8128 5.842)
			(layers "F.Cu" "F.Mask" "F.Paste")
			(net "Net_110")
		)
	)
)
